# S9S_MB_2U (Grand Teton) — schematic netlist excerpt (pin names and nets, part order shuffled) for the footprints in the layout excerpt that follows; sources: Cadence DE-HDL packaged netlist, KiCad conversion of 03242023_DA0F0TMBIJ0_F0T_Motherboard_J_brd_V01_OCP.brd

J104  CONN14_210HP207GBR1  CONN14_210-HP2-07GBR1 IO  pkg HEADER2X7XD  page 201
  \1\  = PU_ESPI_ENABLE_STRAP
  \2\  = JTAG_TRC_PCH_PTI<6>
  \3\  = PU_BIOS_RCVR_BOOT
  \4\  = FM_PCH_BIOS_RCVR_MODE
  \5\  = PU_SWAP_OVERRIDE_N
  \6\  = FM_ADR_COMPLETE
  \7\  = PD_BIOS_IMAGE_SWAP_N
  \8\  = FM_BIOS_IMAGE_SWAP_N
  \9\  = PU_FLASH_SECURITY_STRAP
  \10\  = FM_FLASH_SECURITY_STRAP
  \11\  = PD_ME_RCVR_N
  \12\  = FM_ME_RCVR_N
  \13\  = PD_PASSWORD_CLEAR
  \14\  = FM_PASSWORD_CLEAR_N

(kicad_pcb
	(version 20260206)
	(generator "pcbnew")
	(generator_version "10.0")
	(general
		(thickness 1.6)
		(legacy_teardrops no)
	)
	(paper "A4")
	(title_block
		(title "03242023_DA0F0TMBIJ0_F0T_Motherboard_J_brd_V01_OCP.brd")
		(comment 1 "Grand Teton / footprints 2812-2812 of 6105")
	)
	(layers
		(0 "F.Cu" signal "TOP")
		(4 "In1.Cu" signal "GND")
		(6 "In2.Cu" signal "IN1")
		(8 "In3.Cu" signal "GND1")
		(10 "In4.Cu" signal "IN2")
		(12 "In5.Cu" signal "GND2")
		(14 "In6.Cu" signal "IN3")
		(16 "In7.Cu" signal "GND3")
		(18 "In8.Cu" signal "VCC")
		(20 "In9.Cu" signal "VCC1")
		(22 "In10.Cu" signal "GND4")
		(24 "In11.Cu" signal "IN4")
		(26 "In12.Cu" signal "GND5")
		(28 "In13.Cu" signal "IN5")
		(30 "In14.Cu" signal "GND6")
		(32 "In15.Cu" signal "IN6")
		(34 "In16.Cu" signal "GND7")
		(2 "B.Cu" signal "BOTTOM")
		(9 "F.Adhes" user "F.Adhesive")
		(11 "B.Adhes" user "B.Adhesive")
		(13 "F.Paste" user "Package Geometry/Pastemask Top")
		(15 "B.Paste" user "Package Geometry/Pastemask Bottom")
		(5 "F.SilkS" user "Ref Des/Silkscreen Top")
		(7 "B.SilkS" user "Ref Des/Silkscreen Bottom")
		(1 "F.Mask" user "Board Geometry/Soldermask Top")
		(3 "B.Mask" user "Board Geometry/Soldermask Bottom")
		(17 "Dwgs.User" user "User.Drawings")
		(19 "Cmts.User" user "User.Comments")
		(21 "Eco1.User" user "User.Eco1")
		(23 "Eco2.User" user "User.Eco2")
		(25 "Edge.Cuts" user "Board Geometry/Outline")
		(27 "Margin" user)
		(31 "F.CrtYd" user "Package Geometry/Place Bound Top")
		(29 "B.CrtYd" user "Package Geometry/Place Bound Bottom")
		(35 "F.Fab" user "Ref Des/Assembly Top")
		(33 "B.Fab" user "Ref Des/Assembly Bottom")
	)
	(footprint ""
		(layer "F.Cu")
		(at 426.630084 -44.619926)
		(property "Reference" "J104"
			(at 1.19126 -2.926588 0)
			(unlocked yes)
			(layer "F.SilkS")
			(effects
				(font
					(size 0.7874 0.5842)
					(thickness 0.1524)
				)
				(justify left)
			)
		)
		(property "Value" ""
			(at 0 0 0)
			(layer "F.Fab")
			(effects
				(font
					(size 1.27 1.27)
				)
			)
		)
		(duplicate_pad_numbers_are_jumpers no)
		(fp_line
			(start -1.230122 -1.27)
			(end -1.230122 16.51)
			(stroke
				(width 0.1524)
				(type default)
			)
			(layer "F.SilkS")
		)
		(fp_line
			(start -1.230122 16.51)
			(end 3.770122 16.51)
			(stroke
				(width 0.1524)
				(type default)
			)
			(layer "F.SilkS")
		)
		(fp_line
			(start 3.770122 -1.27)
			(end -1.230122 -1.27)
			(stroke
				(width 0.1524)
				(type default)
			)
			(layer "F.SilkS")
		)
		(fp_line
			(start 3.770122 16.51)
			(end 3.770122 -1.27)
			(stroke
				(width 0.1524)
				(type default)
			)
			(layer "F.SilkS")
		)
		(fp_poly
			(pts
				(xy 0.45974 -2.63144) (xy -0.04826 -1.61544) (xy -0.55626 -2.63144)
			)
			(stroke
				(width 0)
				(type default)
			)
			(fill yes)
			(layer "F.SilkS")
		)
		(fp_line
			(start -1.230122 -1.27)
			(end -1.230122 16.51)
			(stroke
				(width 0.1)
				(type default)
			)
			(layer "F.Fab")
		)
		(fp_line
			(start -1.230122 16.51)
			(end 3.770122 16.51)
			(stroke
				(width 0.1)
				(type default)
			)
			(layer "F.Fab")
		)
		(fp_line
			(start 3.770122 -1.27)
			(end -1.230122 -1.27)
			(stroke
				(width 0.1)
				(type default)
			)
			(layer "F.Fab")
		)
		(fp_line
			(start 3.770122 16.51)
			(end 3.770122 -1.27)
			(stroke
				(width 0.1)
				(type default)
			)
			(layer "F.Fab")
		)
		(fp_poly
			(pts
				(xy 0.508 -2.5146) (xy -0.508 -2.5146) (xy 0 -1.4986)
			)
			(stroke
				(width 0)
				(type default)
			)
			(fill yes)
			(layer "F.Fab")
		)
		(fp_text user "13"
			(at -0.684022 17.95145 0)
			(unlocked yes)
			(layer "F.SilkS")
			(effects
				(font
					(size 0.7874 0.5842)
					(thickness 0.1524)
				)
				(justify left)
			)
		)
		(fp_text user "14"
			(at 1.855978 17.95145 0)
			(unlocked yes)
			(layer "F.SilkS")
			(effects
				(font
					(size 0.7874 0.5842)
					(thickness 0.1524)
				)
				(justify left)
			)
		)
		(fp_text user "2"
			(at 4.372356 -1.470152 0)
			(unlocked yes)
			(layer "F.SilkS")
			(effects
				(font
					(size 0.7874 0.5842)
					(thickness 0.1524)
				)
				(justify left)
			)
		)
		(fp_text user "1"
			(at 0.026416 -2.300732 0)
			(unlocked yes)
			(layer "B.SilkS")
			(effects
				(font
					(size 0.7874 0.5842)
					(thickness 0.1524)
				)
				(justify left mirror)
			)
		)
		(fp_text user "13"
			(at 0.524256 17.173448 0)
			(unlocked yes)
			(layer "B.SilkS")
			(effects
				(font
					(size 0.7874 0.5842)
					(thickness 0.1524)
				)
				(justify left mirror)
			)
		)
		(fp_text user "2"
			(at 3.356356 -1.955292 0)
			(unlocked yes)
			(layer "B.SilkS")
			(effects
				(font
					(size 0.7874 0.5842)
					(thickness 0.1524)
				)
				(justify left mirror)
			)
		)
		(fp_text user "14"
			(at 4.273296 17.249648 0)
			(unlocked yes)
			(layer "B.SilkS")
			(effects
				(font
					(size 0.7874 0.5842)
					(thickness 0.1524)
				)
				(justify left mirror)
			)
		)
		(fp_text user "1"
			(at 0.091948 -0.9779 270)
			(unlocked yes)
			(layer "B.Fab")
			(effects
				(font
					(size 0.7874 0.5842)
					(thickness 0.1524)
				)
				(justify left mirror)
			)
		)
		(fp_text user "13"
			(at 0.091948 17.7038 270)
			(unlocked yes)
			(layer "B.Fab")
			(effects
				(font
					(size 0.7874 0.5842)
					(thickness 0.1524)
				)
				(justify left mirror)
			)
		)
		(fp_text user "2"
			(at 2.631948 -0.9779 270)
			(unlocked yes)
			(layer "B.Fab")
			(effects
				(font
					(size 0.7874 0.5842)
					(thickness 0.1524)
				)
				(justify left mirror)
			)
		)
		(fp_text user "14"
			(at 2.631948 17.7038 270)
			(unlocked yes)
			(layer "B.Fab")
			(effects
				(font
					(size 0.7874 0.5842)
					(thickness 0.1524)
				)
				(justify left mirror)
			)
		)
		(fp_text user "13"
			(at 0.091948 16.5862 270)
			(unlocked yes)
			(layer "F.Fab")
			(effects
				(font
					(size 0.7874 0.5842)
					(thickness 0.1524)
				)
				(justify left)
			)
		)
		(fp_text user "2"
			(at 2.631948 -2.0701 270)
			(unlocked yes)
			(layer "F.Fab")
			(effects
				(font
					(size 0.7874 0.5842)
					(thickness 0.1524)
				)
				(justify left)
			)
		)
		(fp_text user "14"
			(at 2.631948 16.5862 270)
			(unlocked yes)
			(layer "F.Fab")
			(effects
				(font
					(size 0.7874 0.5842)
					(thickness 0.1524)
				)
				(justify left)
			)
		)
		(pad "1" thru_hole rect
			(at 0 0 270)
			(size 1.5494 1.5494)
			(drill 1.0414)
			(layers "*.Cu" "*.Mask")
			(remove_unused_layers no)
			(net "PU_ESPI_ENABLE_STRAP")
			(clearance 0)
			(padstack
				(mode front_inner_back)
				(layer "Inner"
					(shape circle)
					(size 1.5494 1.5494)
					(clearance 0)
				)
				(layer "B.Cu"
					(shape rect)
					(size 1.5494 1.5494)
					(clearance 0)
				)
			)
		)
		(pad "2" thru_hole circle
			(at 2.54 0 270)
			(size 1.5494 1.5494)
			(drill 1.0414)
			(layers "*.Cu" "*.Mask")
			(remove_unused_layers no)
			(net "JTAG_TRC_PCH_PTI<6>")
			(clearance 0)
		)
		(pad "3" thru_hole circle
			(at 0 2.54 270)
			(size 1.5494 1.5494)
			(drill 1.0414)
			(layers "*.Cu" "*.Mask")
			(remove_unused_layers no)
			(net "PU_BIOS_RCVR_BOOT")
			(clearance 0)
		)
		(pad "4" thru_hole circle
			(at 2.54 2.54 270)
			(size 1.5494 1.5494)
			(drill 1.0414)
			(layers "*.Cu" "*.Mask")
			(remove_unused_layers no)
			(net "FM_PCH_BIOS_RCVR_MODE")
			(clearance 0)
		)
		(pad "5" thru_hole circle
			(at 0 5.08 270)
			(size 1.5494 1.5494)
			(drill 1.0414)
			(layers "*.Cu" "*.Mask")
			(remove_unused_layers no)
			(net "PU_SWAP_OVERRIDE_N")
			(clearance 0)
		)
		(pad "6" thru_hole circle
			(at 2.54 5.08 270)
			(size 1.5494 1.5494)
			(drill 1.0414)
			(layers "*.Cu" "*.Mask")
			(remove_unused_layers no)
			(net "FM_ADR_COMPLETE")
			(clearance 0)
		)
		(pad "7" thru_hole circle
			(at 0 7.62 270)
			(size 1.5494 1.5494)
			(drill 1.0414)
			(layers "*.Cu" "*.Mask")
			(remove_unused_layers no)
			(net "PD_BIOS_IMAGE_SWAP_N")
			(clearance 0)
		)
		(pad "8" thru_hole circle
			(at 2.54 7.62 270)
			(size 1.5494 1.5494)
			(drill 1.0414)
			(layers "*.Cu" "*.Mask")
			(remove_unused_layers no)
			(net "FM_BIOS_IMAGE_SWAP_N")
			(clearance 0)
		)
		(pad "9" thru_hole circle
			(at 0 10.16 270)
			(size 1.5494 1.5494)
			(drill 1.0414)
			(layers "*.Cu" "*.Mask")
			(remove_unused_layers no)
			(net "PU_FLASH_SECURITY_STRAP")
			(clearance 0)
		)
		(pad "10" thru_hole circle
			(at 2.54 10.16 270)
			(size 1.5494 1.5494)
			(drill 1.0414)
			(layers "*.Cu" "*.Mask")
			(remove_unused_layers no)
			(net "FM_FLASH_SECURITY_STRAP")
			(clearance 0)
		)
		(pad "11" thru_hole circle
			(at 0 12.7 270)
			(size 1.5494 1.5494)
			(drill 1.0414)
			(layers "*.Cu" "*.Mask")
			(remove_unused_layers no)
			(net "PD_ME_RCVR_N")
			(clearance 0)
		)
		(pad "12" thru_hole circle
			(at 2.54 12.7 270)
			(size 1.5494 1.5494)
			(drill 1.0414)
			(layers "*.Cu" "*.Mask")
			(remove_unused_layers no)
			(net "FM_ME_RCVR_N")
			(clearance 0)
		)
		(pad "13" thru_hole circle
			(at 0 15.24 270)
			(size 1.5494 1.5494)
			(drill 1.0414)
			(layers "*.Cu" "*.Mask")
			(remove_unused_layers no)
			(net "PD_PASSWORD_CLEAR")
			(clearance 0)
		)
		(pad "14" thru_hole circle
			(at 2.54 15.24 270)
			(size 1.5494 1.5494)
			(drill 1.0414)
			(layers "*.Cu" "*.Mask")
			(remove_unused_layers no)
			(net "FM_PASSWORD_CLEAR_N")
			(clearance 0)
		)
	)
)
